# T6G (Grand Teton) — schematic netlist excerpt (pin names and nets, part order shuffled) for the footprints in the layout excerpt that follows; sources: Cadence DE-HDL packaged netlist, KiCad conversion of 04192023_DAF0TMB3IC0_F0TG_MB_C_brd_V02_OCP.brd

PC377_1  Q_CAP  1UF 25V 10% X6S  pkg C0402  page 218 : A = SW_P12V_AUX_PVDDCR_CPU1_P1_FLT ; B = GND
R6178  Q_RES  1K 1% EMPTY  pkg 0402LF  page 112 : A = FM_P2E_BUF2_SD_TH ; B = GND

(kicad_pcb
	(version 20260206)
	(generator "pcbnew")
	(generator_version "10.0")
	(general
		(thickness 1.6)
		(legacy_teardrops no)
	)
	(paper "A4")
	(title_block
		(title "04192023_DAF0TMB3IC0_F0TG_MB_C_brd_V02_OCP.brd")
		(comment 1 "Grand Teton / footprints 1165-1166 of 8354")
	)
	(layers
		(0 "F.Cu" signal "TOP")
		(4 "In1.Cu" signal "GND")
		(6 "In2.Cu" signal "IN1")
		(8 "In3.Cu" signal "GND1")
		(10 "In4.Cu" signal "IN2")
		(12 "In5.Cu" signal "GND2")
		(14 "In6.Cu" signal "IN3")
		(16 "In7.Cu" signal "GND3")
		(18 "In8.Cu" signal "VCC")
		(20 "In9.Cu" signal "VCC1")
		(22 "In10.Cu" signal "GND4")
		(24 "In11.Cu" signal "IN4")
		(26 "In12.Cu" signal "GND5")
		(28 "In13.Cu" signal "IN5")
		(30 "In14.Cu" signal "GND6")
		(32 "In15.Cu" signal "IN6")
		(34 "In16.Cu" signal "GND7")
		(2 "B.Cu" signal "BOTTOM")
		(9 "F.Adhes" user "F.Adhesive")
		(11 "B.Adhes" user "B.Adhesive")
		(13 "F.Paste" user "Package Geometry/Pastemask Top")
		(15 "B.Paste" user "Package Geometry/Pastemask Bottom")
		(5 "F.SilkS" user "Ref Des/Silkscreen Top")
		(7 "B.SilkS" user "Ref Des/Silkscreen Bottom")
		(1 "F.Mask" user "Board Geometry/Soldermask Top")
		(3 "B.Mask" user "Board Geometry/Soldermask Bottom")
		(17 "Dwgs.User" user "User.Drawings")
		(19 "Cmts.User" user "User.Comments")
		(21 "Eco1.User" user "User.Eco1")
		(23 "Eco2.User" user "User.Eco2")
		(25 "Edge.Cuts" user "Board Geometry/Outline")
		(27 "Margin" user)
		(31 "F.CrtYd" user "Package Geometry/Place Bound Top")
		(29 "B.CrtYd" user "Package Geometry/Place Bound Bottom")
		(35 "F.Fab" user "Ref Des/Assembly Top")
		(33 "B.Fab" user "Ref Des/Assembly Bottom")
	)
	(footprint ""
		(layer "F.Cu")
		(at 90.75674 -335.128616 -90)
		(property "Reference" "PC377_1"
			(at 0 0 270)
			(layer "F.SilkS")
			(hide yes)
			(effects
				(font
					(size 1.27 1.27)
				)
			)
		)
		(property "Value" ""
			(at 0 0 270)
			(layer "F.Fab")
			(effects
				(font
					(size 1.27 1.27)
				)
			)
		)
		(duplicate_pad_numbers_are_jumpers no)
		(fp_line
			(start -0.7874 0.4064)
			(end -0.7874 -0.4064)
			(stroke
				(width 0.1524)
				(type default)
			)
			(layer "F.SilkS")
		)
		(fp_line
			(start 0.7874 0.4064)
			(end -0.7874 0.4064)
			(stroke
				(width 0.1524)
				(type default)
			)
			(layer "F.SilkS")
		)
		(fp_line
			(start -0.7874 -0.4064)
			(end 0.7874 -0.4064)
			(stroke
				(width 0.1524)
				(type default)
			)
			(layer "F.SilkS")
		)
		(fp_line
			(start 0.7874 -0.4064)
			(end 0.7874 0.4064)
			(stroke
				(width 0.1524)
				(type default)
			)
			(layer "F.SilkS")
		)
		(fp_line
			(start -0.67945 0.3048)
			(end -0.67945 -0.305054)
			(stroke
				(width 0.1)
				(type default)
			)
			(layer "F.Fab")
		)
		(fp_line
			(start -0.12065 0.3048)
			(end -0.67945 0.3048)
			(stroke
				(width 0.1)
				(type default)
			)
			(layer "F.Fab")
		)
		(fp_line
			(start 0.120396 0.3048)
			(end 0.120396 0.2794)
			(stroke
				(width 0.1)
				(type default)
			)
			(layer "F.Fab")
		)
		(fp_line
			(start 0.67945 0.3048)
			(end 0.120396 0.3048)
			(stroke
				(width 0.1)
				(type default)
			)
			(layer "F.Fab")
		)
		(fp_line
			(start -0.12065 0.2794)
			(end -0.12065 0.3048)
			(stroke
				(width 0.1)
				(type default)
			)
			(layer "F.Fab")
		)
		(fp_line
			(start 0.120396 0.2794)
			(end -0.12065 0.2794)
			(stroke
				(width 0.1)
				(type default)
			)
			(layer "F.Fab")
		)
		(fp_line
			(start -0.12065 -0.2794)
			(end 0.12065 -0.2794)
			(stroke
				(width 0.1)
				(type default)
			)
			(layer "F.Fab")
		)
		(fp_line
			(start 0.12065 -0.2794)
			(end 0.12065 -0.3048)
			(stroke
				(width 0.1)
				(type default)
			)
			(layer "F.Fab")
		)
		(fp_line
			(start 0.12065 -0.3048)
			(end 0.67945 -0.3048)
			(stroke
				(width 0.1)
				(type default)
			)
			(layer "F.Fab")
		)
		(fp_line
			(start 0.67945 -0.3048)
			(end 0.67945 0.3048)
			(stroke
				(width 0.1)
				(type default)
			)
			(layer "F.Fab")
		)
		(fp_line
			(start -0.67945 -0.305054)
			(end -0.12065 -0.305054)
			(stroke
				(width 0.1)
				(type default)
			)
			(layer "F.Fab")
		)
		(fp_line
			(start -0.12065 -0.305054)
			(end -0.12065 -0.2794)
			(stroke
				(width 0.1)
				(type default)
			)
			(layer "F.Fab")
		)
		(pad "1" smd circle
			(at -0.40005 0 270)
			(size 0 0)
			(layers "F.Cu" "F.Mask" "F.Paste")
			(net "SW_P12V_AUX_PVDDCR_CPU1_P1_FLT")
		)
		(pad "2" smd circle
			(at 0.40005 0 270)
			(size 0 0)
			(layers "F.Cu" "F.Mask" "F.Paste")
			(net "GND")
		)
	)
	(footprint ""
		(layer "F.Cu")
		(at 15.094458 -418.690298 -90)
		(property "Reference" "R6178"
			(at 0 0 270)
			(layer "F.SilkS")
			(hide yes)
			(effects
				(font
					(size 1.27 1.27)
				)
			)
		)
		(property "Value" ""
			(at 0 0 270)
			(layer "F.Fab")
			(effects
				(font
					(size 1.27 1.27)
				)
			)
		)
		(duplicate_pad_numbers_are_jumpers no)
		(fp_line
			(start -0.7874 0.4064)
			(end -0.7874 -0.4064)
			(stroke
				(width 0.1524)
				(type default)
			)
			(layer "F.SilkS")
		)
		(fp_line
			(start 0.7874 0.4064)
			(end -0.7874 0.4064)
			(stroke
				(width 0.1524)
				(type default)
			)
			(layer "F.SilkS")
		)
		(fp_line
			(start -0.7874 -0.4064)
			(end 0.7874 -0.4064)
			(stroke
				(width 0.1524)
				(type default)
			)
			(layer "F.SilkS")
		)
		(fp_line
			(start 0.7874 -0.4064)
			(end 0.7874 0.4064)
			(stroke
				(width 0.1524)
				(type default)
			)
			(layer "F.SilkS")
		)
		(fp_line
			(start -0.67945 0.3048)
			(end -0.67945 -0.305054)
			(stroke
				(width 0.1)
				(type default)
			)
			(layer "F.Fab")
		)
		(fp_line
			(start -0.12065 0.3048)
			(end -0.67945 0.3048)
			(stroke
				(width 0.1)
				(type default)
			)
			(layer "F.Fab")
		)
		(fp_line
			(start 0.120396 0.3048)
			(end 0.120396 0.2794)
			(stroke
				(width 0.1)
				(type default)
			)
			(layer "F.Fab")
		)
		(fp_line
			(start 0.67945 0.3048)
			(end 0.120396 0.3048)
			(stroke
				(width 0.1)
				(type default)
			)
			(layer "F.Fab")
		)
		(fp_line
			(start -0.12065 0.2794)
			(end -0.12065 0.3048)
			(stroke
				(width 0.1)
				(type default)
			)
			(layer "F.Fab")
		)
		(fp_line
			(start 0.120396 0.2794)
			(end -0.12065 0.2794)
			(stroke
				(width 0.1)
				(type default)
			)
			(layer "F.Fab")
		)
		(fp_line
			(start -0.12065 -0.2794)
			(end 0.12065 -0.2794)
			(stroke
				(width 0.1)
				(type default)
			)
			(layer "F.Fab")
		)
		(fp_line
			(start 0.12065 -0.2794)
			(end 0.12065 -0.3048)
			(stroke
				(width 0.1)
				(type default)
			)
			(layer "F.Fab")
		)
		(fp_line
			(start 0.12065 -0.3048)
			(end 0.67945 -0.3048)
			(stroke
				(width 0.1)
				(type default)
			)
			(layer "F.Fab")
		)
		(fp_line
			(start 0.67945 -0.3048)
			(end 0.67945 0.3048)
			(stroke
				(width 0.1)
				(type default)
			)
			(layer "F.Fab")
		)
		(fp_line
			(start -0.67945 -0.305054)
			(end -0.12065 -0.305054)
			(stroke
				(width 0.1)
				(type default)
			)
			(layer "F.Fab")
		)
		(fp_line
			(start -0.12065 -0.305054)
			(end -0.12065 -0.2794)
			(stroke
				(width 0.1)
				(type default)
			)
			(layer "F.Fab")
		)
		(pad "1" smd circle
			(at -0.40005 0 270)
			(size 0 0)
			(layers "F.Cu" "F.Mask" "F.Paste")
			(net "FM_P2E_BUF2_SD_TH")
		)
		(pad "2" smd circle
			(at 0.40005 0 270)
			(size 0 0)
			(layers "F.Cu" "F.Mask" "F.Paste")
			(net "GND")
		)
	)
)
